# T6G (Grand Teton) — schematic parts with pin connectivity, parts 2615–2616 of 8303; source: Cadence DE-HDL packaged netlist (pstxprt.dat, pstxnet.dat, pstchip.dat)

J38  SCONN168_ME1016810202011  IO  pkg CON_F168S2H7D_P0-6W2-95_LUH  page 131
  A1  GND_A1  POWER  = GND
  A2  GND_A2  POWER  = GND
  A3  GND_A3  POWER  = GND
  A4  GND_A4  POWER  = GND
  A5  GND_A5  POWER  = GND
  A6  GND_A6  POWER  = GND
  A7  SMCLK  OUT  = SMB_OCP_SFF_3V3AUX_BUF_R_SCL
  A8  SMDAT  BI  = SMB_OCP_SFF_3V3AUX_BUF_R_SDA
  A9  \smrst#\  OUT  = RST_SMB_OCP_SFF_N
  A10  \prsnta#\  OUT  = OCP_SFF_PRSNTA_R_N
  A11  \perst1#\  OUT  = RST_PERST1_OCP_SFF_N
  A12  \prsntb2#\  IN  = OCP_SFF_PRSNT2_R_N
  A13  GND_A13  POWER  = GND
  A14  REFCLKN1  OUT  = CLK_100M_CPU0_CLK03_DN
  A15  REFCLKP1  OUT  = CLK_100M_CPU0_CLK03_DP
  A16  GND_A16  POWER  = GND
  A17  PERN0  IN  = P5E_CPU0_G3_RX_DN<0>
  A18  PERP0  IN  = P5E_CPU0_G3_RX_DP<0>
  A19  GND_A19  POWER  = GND
  A20  PERN1  IN  = P5E_CPU0_G3_RX_DN<1>
  A21  PERP1  IN  = P5E_CPU0_G3_RX_DP<1>
  A22  GND_A22  POWER  = GND
  A23  PERN2  IN  = P5E_CPU0_G3_RX_DN<2>
  A24  PERP2  IN  = P5E_CPU0_G3_RX_DP<2>
  A25  GND_A25  POWER  = GND
  A26  PERN3  IN  = P5E_CPU0_G3_RX_DN<3>
  A27  PERP3  IN  = P5E_CPU0_G3_RX_DP<3>
  A28  GND_A28  POWER  = GND
  A29  GND_A29  POWER  = GND
  A30  PERN4  IN  = P5E_CPU0_G3_RX_DN<4>
  A31  PERP4  IN  = P5E_CPU0_G3_RX_DP<4>
  A32  GND_A32  POWER  = GND
  A33  PERN5  IN  = P5E_CPU0_G3_RX_DN<5>
  A34  PERP5  IN  = P5E_CPU0_G3_RX_DP<5>
  A35  GND_A35  POWER  = GND
  A36  PERN6  IN  = P5E_CPU0_G3_RX_DN<6>
  A37  PERP6  IN  = P5E_CPU0_G3_RX_DP<6>
  A38  GND_A38  POWER  = GND
  A39  PERN7  IN  = P5E_CPU0_G3_RX_DN<7>
  A40  PERP7  IN  = P5E_CPU0_G3_RX_DP<7>
  A41  GND_A41  POWER  = GND
  A42  \prsntb1#\  IN  = OCP_SFF_PRSNT1_R_N
  A43  GND_A43  POWER  = GND
  A44  PERN8  IN  = P5E_CPU0_G3_RX_DN<8>
  A45  PERP8  IN  = P5E_CPU0_G3_RX_DP<8>
  A46  GND_A46  POWER  = GND
  A47  PERN9  IN  = P5E_CPU0_G3_RX_DN<9>
  A48  PERP9  IN  = P5E_CPU0_G3_RX_DP<9>
  A49  GND_A49  POWER  = GND
  A50  PERN10  IN  = P5E_CPU0_G3_RX_DN<10>
  A51  PERP10  IN  = P5E_CPU0_G3_RX_DP<10>
  A52  GND_A52  POWER  = GND
  A53  PERN11  IN  = P5E_CPU0_G3_RX_DN<11>
  A54  PERP11  IN  = P5E_CPU0_G3_RX_DP<11>
  A55  GND_A55  POWER  = GND
  A56  PERN12  IN  = P5E_CPU0_G3_RX_DN<12>
  A57  PERP12  IN  = P5E_CPU0_G3_RX_DP<12>
  A58  GND_A58  POWER  = GND
  A59  PERN13  IN  = P5E_CPU0_G3_RX_DN<13>
  A60  PERP13  IN  = P5E_CPU0_G3_RX_DP<13>
  A61  GND_A61  POWER  = GND
  A62  PERN14  IN  = P5E_CPU0_G3_RX_DN<14>
  A63  PERP14  IN  = P5E_CPU0_G3_RX_DP<14>
  A64  GND_A64  POWER  = GND
  A65  PERN15  IN  = P5E_CPU0_G3_RX_DN<15>
  A66  PERP15  IN  = P5E_CPU0_G3_RX_DP<15>
  A67  GND_A67  POWER  = GND
  A68  USB_DATN  BI  = USB2_P11_DN
  A69  USB_DATP  BI  = USB2_P11_DP
  A70  \pwrbrk0#\  BI  = OCP_SFF_PWRBRK_N
  B1  \+12v_edge_b1\  POWER  = P12V_OCP_SFF_R
  B2  \+12v_edge_b2\  POWER  = P12V_OCP_SFF_R
  B3  \+12v_edge_b3\  POWER  = P12V_OCP_SFF_R
  B4  \+12v_edge_b4\  POWER  = P12V_OCP_SFF_R
  B5  \+12v_edge_b5\  POWER  = P12V_OCP_SFF_R
  B6  \+12v_edge_b6\  POWER  = P12V_OCP_SFF_R
  B7  \bif0#\  OUT  = OCP_SFF_BIF0_R_N
  B8  \bif1#\  OUT  = OCP_SFF_BIF1_R_N
  B9  \bif2#\  OUT  = OCP_SFF_BIF2_R_N
  B10  \perst0#\  OUT  = RST_PERST0_OCP_SFF_N
  B11  \+3.3v_edge\  POWER  = P3V3_OCP_SFF
  B12  AUX_PWR_EN  OUT  = OCP_SFF_AUX_PWR_EN_R
  B13  GND_B13  POWER  = GND
  B14  REFCLKN0  IN  = CLK_100M_CPU0_CLK02_DN
  B15  REFCLKP0  OUT  = CLK_100M_CPU0_CLK02_DP
  B16  GND_B16  POWER  = GND
  B17  PETN0  OUT  = P5E_CPU0_G3_TX_C_DP<0>
  B18  PETP0  OUT  = P5E_CPU0_G3_TX_C_DN<0>
  B19  GND_B19  POWER  = GND
  B20  PETN1  OUT  = P5E_CPU0_G3_TX_C_DP<1>
  B21  PETP1  OUT  = P5E_CPU0_G3_TX_C_DN<1>
  B22  GND_B22  POWER  = GND
  B23  PETN2  OUT  = P5E_CPU0_G3_TX_C_DP<2>
  B24  PETP2  OUT  = P5E_CPU0_G3_TX_C_DN<2>
  B25  GND_B25  POWER  = GND
  B26  PETN3  OUT  = P5E_CPU0_G3_TX_C_DP<3>
  B27  PETP3  OUT  = P5E_CPU0_G3_TX_C_DN<3>
  B28  GND_B28  POWER  = GND
  B29  GND_B29  POWER  = GND
  B30  PETN4  OUT  = P5E_CPU0_G3_TX_C_DP<4>
  B31  PETP4  OUT  = P5E_CPU0_G3_TX_C_DN<4>
  B32  GND_B32  POWER  = GND
  B33  PETN5  OUT  = P5E_CPU0_G3_TX_C_DP<5>
  B34  PETP5  OUT  = P5E_CPU0_G3_TX_C_DN<5>
  B35  GND_B35  POWER  = GND
  B36  PETN6  OUT  = P5E_CPU0_G3_TX_C_DP<6>
  B37  PETP6  OUT  = P5E_CPU0_G3_TX_C_DN<6>
  B38  GND_B38  POWER  = GND
  B39  PETN7  OUT  = P5E_CPU0_G3_TX_C_DP<7>
  B40  PETP7  OUT  = P5E_CPU0_G3_TX_C_DN<7>
  B41  GND_B41  POWER  = GND
  B42  \prsntb0#\  IN  = OCP_SFF_PRSNT0_R_N
  B43  GND_B43  POWER  = GND
  B44  PETN8  OUT  = P5E_CPU0_G3_TX_C_DP<8>
  B45  PETP8  OUT  = P5E_CPU0_G3_TX_C_DN<8>
  B46  GND_B46  POWER  = GND
  B47  PETN9  OUT  = P5E_CPU0_G3_TX_C_DP<9>
  B48  PETP9  OUT  = P5E_CPU0_G3_TX_C_DN<9>
  B49  GND_B49  POWER  = GND
  B50  PETN10  OUT  = P5E_CPU0_G3_TX_C_DP<10>
  B51  PETP10  OUT  = P5E_CPU0_G3_TX_C_DN<10>
  B52  GND_B52  POWER  = GND
  B53  PETN11  OUT  = P5E_CPU0_G3_TX_C_DP<11>
  B54  PETP11  OUT  = P5E_CPU0_G3_TX_C_DN<11>
  B55  GND_B55  POWER  = GND
  B56  PETN12  OUT  = P5E_CPU0_G3_TX_C_DP<12>
  B57  PETP12  OUT  = P5E_CPU0_G3_TX_C_DN<12>
  B58  GND_B58  POWER  = GND
  B59  PETN13  OUT  = P5E_CPU0_G3_TX_C_DP<13>
  B60  PETP13  OUT  = P5E_CPU0_G3_TX_C_DN<13>
  B61  GND_B61  POWER  = GND
  B62  PETN14  OUT  = P5E_CPU0_G3_TX_C_DP<14>
  B63  PETP14  OUT  = P5E_CPU0_G3_TX_C_DN<14>
  B64  GND_B64  POWER  = GND
  B65  PETN15  OUT  = P5E_CPU0_G3_TX_C_DP<15>
  B66  PETP15  OUT  = P5E_CPU0_G3_TX_C_DN<15>
  B67  GND_B67  POWER  = GND
  B68  RFU1_NC_B68  TRI  = TP_OCP_SFF_B68
  B69  RFU1_NC_B69  TRI  = TP_OCP_SFF_B69
  B70  \prsntb3#\  IN  = OCP_SFF_PRSNT3_R_N
  G1  G1  POWER  = GND
  G2  G2  POWER  = GND
  G3  G3  POWER  = GND
  G4  G4  POWER  = GND
  G5  G5  POWER  = GND
  OA1  \perst2#\  OUT  = RST_PERST2_OCP_SFF_N
  OA2  \perst3#\  OUT  = RST_PERST3_OCP_SFF_N
  OA3  \wake#\  IN  = IRQ_LVC3_OCP_SFF_WAKE_N
  OA4  RBT_ARB_IN  IN  = OCP_SFF_ISO1_RBT_ARB_IN
  OA5  RBT_ARB_OUT  OUT  = OCP_SFF_ISO2_RBT_ARB_OUT
  OA6  SLOT_ID1  OUT  = OCP_SFF_ID1
  OA7  RBT_TX_EN  OUT  = NCSI_OCP_SFF_TX_EN
  OA8  RBT_TXD1  OUT  = NCSI_OCP_SFF_TXD1
  OA9  RBT_TXD0  OUT  = NCSI_OCP_SFF_TXD0
  OA10  GND_OA10  POWER  = GND
  OA11  REFCLKN3  OUT  = CLK_100M_CPU0_CLK05_DN
  OA12  REFCLKP3  OUT  = CLK_100M_CPU0_CLK05_DP
  OA13  GND_OA13  POWER  = GND
  OA14  RBT_CLK_IN  OUT  = CLK_50M_NCSI_OCP_SFF_ISO
  OB1  NIC_PWR_GOOD  IN  = FM_OCP_SFF_PWR_GOOD
  OB2  MAIN_PWR_EN  OUT  = OCP_SFF_MAIN_PWR_EN_R
  OB3  \ld#\  OUT  = SGPIO_OCP_SFF_LD_N
  OB4  DATA_IN  IN  = SGPIO_OCP_SFF_DATAIN
  OB5  DATA_OUT  OUT  = SGPIO_OCP_SFF_DATAOUT
  OB6  CLK  OUT  = SGPIO_OCP_SFF_CLK
  OB7  SLOT_ID0  OUT  = OCP_SFF_ID0
  OB8  RBT_RXD1  IN  = NCSI_OCP_SFF_RXD1
  OB9  RBT_RXD0  IN  = NCSI_OCP_SFF_RXD0
  OB10  GND_OB10  POWER  = GND
  OB11  REFCLKN2  OUT  = CLK_100M_CPU0_CLK04_DN
  OB12  REFCLKP2  OUT  = CLK_100M_CPU0_CLK04_DP
  OB13  GND_OB13  POWER  = GND
  OB14  RBT_CRS_DV  OUT  = NCSI_OCP_SFF_CRS_DV

J41  SCONN168_ME1016810202011  IO  pkg CON_F168S2H7D_P0-6W2-95_LUH  page 150
  A1  GND_A1  POWER  = SMB_OCP_SFF_3V3AUX_SCL_R0
  A2  GND_A2  POWER  = SMB_OCP_SFF_3V3AUX_SDA_R0
  A3  GND_A3  POWER  = SMB_CPU0_CPU1_APML_SCL_R
  A4  GND_A4  POWER  = SMB_CPU0_CPU1_APML_SDA_R
  A5  GND_A5  POWER  = SMB_VR_3V3AUX_SCL_R0
  A6  GND_A6  POWER  = SMB_VR_3V3AUX_SDA_R0
  A7  SMCLK  OUT  = SMB_CPU0_CPU1_SEC_SCL_R
  A8  SMDAT  BI  = SMB_CPU0_CPU1_SEC_SDA_R
  A9  \smrst#\  OUT  = I3C_BMC_SWB_SCL
  A10  \prsnta#\  OUT  = I3C_BMC_SWB_SDA
  A11  \perst1#\  OUT  = SMB_OCP_V3_2_3V3AUX_SCL_R0
  A12  \prsntb2#\  IN  = SMB_OCP_V3_2_3V3AUX_SDA_R0
  A13  GND_A13  POWER  = GND
  A14  REFCLKN1  OUT  = CLK_100M_CPU0_CLK01_DP
  A15  REFCLKP1  OUT  = CLK_100M_CPU0_CLK01_DN
  A16  GND_A16  POWER  = GND
  A17  PERN0  IN  = P2E_CPU0_P5_TX_C_DP
  A18  PERP0  IN  = P2E_CPU0_P5_TX_C_DN
  A19  GND_A19  POWER  = GND
  A20  PERN1  IN  = P2E_CPU0_P5_RX_DP
  A21  PERP1  IN  = P2E_CPU0_P5_RX_DN
  A22  GND_A22  POWER  = GND
  A23  PERN2  IN  = SMB_PCIE0_3V3AUX_SCL
  A24  PERP2  IN  = SMB_PCIE0_3V3AUX_SDA
  A25  GND_A25  POWER  = SMB_PMBUS_3V3AUX_SCL_R0
  A26  PERN3  IN  = SMB_PMBUS_3V3AUX_SDA_R0
  A27  PERP3  IN  = SMB_1_PLD_3V3AUX_SCL_R3
  A28  GND_A28  POWER  = SMB_1_PLD_3V3AUX_SDA_R3
  A29  GND_A29  POWER  = SMB_FAN_3V3AUX_SCL
  A30  PERN4  IN  = SMB_FAN_3V3AUX_SDA
  A31  PERP4  IN  = SMB_PCIE2_3V3AUX_SCL_R0
  A32  GND_A32  POWER  = SMB_PCIE2_3V3AUX_SDA_R0
  A33  PERN5  IN  = GND
  A34  PERP5  IN  = JTAG_SCM_TCK
  A35  GND_A35  POWER  = JTAG_SCM_TMS
  A36  PERN6  IN  = JTAG_SCM_TDI_R
  A37  PERP6  IN  = JTAG_SCM_TDO_R
  A38  GND_A38  POWER  = SMB_PCIE3_3V3AUX_SCL_R
  A39  PERN7  IN  = SMB_PCIE3_3V3AUX_SDA_R
  A40  PERP7  IN  = SMB_HOST_CLK_3V3AUX_SCL_R0
  A41  GND_A41  POWER  = SMB_HOST_CLK_3V3AUX_SDA_R0
  A42  \prsntb1#\  IN  = GND
  A43  GND_A43  POWER  = FW_RECOVERY
  A44  PERN8  IN  = PWRGD_PS_PWROK_R
  A45  PERP8  IN  = TP_STBY_EN
  A46  GND_A46  POWER  = RST_MB_STBY_R_N
  A47  PERN9  IN  = SCM_SYS_PWRBTN_R_N
  A48  PERP9  IN  = SCM_SYS_PWROK_R1
  A49  GND_A49  POWER  = SCM_HDT_DBREQ_N
  A50  PERN10  IN  = PU_JTAG_DBP_BMC_PRDY_N
  A51  PERP10  IN  = FM_RST_PERST_SCM_N
  A52  GND_A52  POWER  = FM_UARTSW_MSB_R
  A53  PERN11  IN  = SCM_ROT_CPU_RST_N
  A54  PERP11  IN  = TP_CHASI
  A55  GND_A55  POWER  = FM_UARTSW_LSB_R
  A56  PERN12  IN  = IRQ0_A56
  A57  PERP12  IN  = FM_SCM_PRSNT1_N
  A58  GND_A58  POWER  = GND
  A59  PERN13  IN  = USB3_CPU0_BMC_RX_DP
  A60  PERP13  IN  = USB3_CPU0_BMC_RX_DN
  A61  GND_A61  POWER  = GND
  A62  PERN14  IN  = TP_PCIE_RXP<1>
  A63  PERP14  IN  = TP_PCIE_RXN<1>
  A64  GND_A64  POWER  = GND
  A65  PERN15  IN  = P2E_MB_BMC_RX_BUF_DP<0>
  A66  PERP15  IN  = P2E_MB_BMC_RX_BUF_DN<0>
  A67  GND_A67  POWER  = GND
  A68  USB_DATN  BI  = CLK_100M_BMC_RC_DP
  A69  USB_DATP  BI  = CLK_100M_BMC_RC_DN
  A70  \pwrbrk0#\  BI  = GND
  B1  \+12v_edge_b1\  POWER  = CLK_ESPI_CPU0_CLK1
  B2  \+12v_edge_b2\  POWER  = ESPI_CPU0_CS1_N
  B3  \+12v_edge_b3\  POWER  = ESPI_CPU0_ALERT_N
  B4  \+12v_edge_b4\  POWER  = RST_ESPI_CPU0_RSTOUT_N
  B5  \+12v_edge_b5\  POWER  = ESPI_CPU0_D0
  B6  \+12v_edge_b6\  POWER  = ESPI_CPU0_D1
  B7  \bif0#\  OUT  = ESPI_CPU0_D2
  B8  \bif1#\  OUT  = ESPI_CPU0_D3
  B9  \bif2#\  OUT  = FM_LPC_ESPI_SEL
  B10  \perst0#\  OUT  = GND
  B11  \+3.3v_edge\  POWER  = SPI_CPU0_LVC3_SCM_CLK
  B12  AUX_PWR_EN  OUT  = SPI_CPU0_LVC3_SCM_CS0_N
  B13  GND_B13  POWER  = SPI_CPU0_LVC3_SCM_D0
  B14  REFCLKN0  IN  = SPI_CPU0_LVC3_SCM_D1
  B15  REFCLKP0  OUT  = SPI_CPU0_LVC3_SCM_D2
  B16  GND_B16  POWER  = SPI_CPU0_LVC3_SCM_D3
  B17  PETN0  OUT  = GND
  B18  PETP0  OUT  = CLK_50M_RMII_BMC_OCP
  B19  GND_B19  POWER  = RMII_OCP_BMC_CRSDV
  B20  PETN1  OUT  = RMII_BMC_OCP_TX_EN
  B21  PETP1  OUT  = RMII_BMC_OCP_TXD_0
  B22  GND_B22  POWER  = RMII_BMC_OCP_TXD_1
  B23  PETN2  OUT  = RMII_BMC_OCP_RX_ER
  B24  PETP2  OUT  = RMII_OCP_BMC_RXD_0
  B25  GND_B25  POWER  = RMII_OCP_BMC_RXD_1
  B26  PETN3  OUT  = GND
  B27  PETP3  OUT  = TP_PECI_BMC
  B28  GND_B28  POWER  = TP_PVCCIO_PECI_BMC
  B29  GND_B29  POWER  = SGPIO_SCM_DO_R_<0>
  B30  PETN4  OUT  = SGPIO_SCM_CLK_R_<0>
  B31  PETP4  OUT  = SGPIO_SCM_DI_R_<0>
  B32  GND_B32  POWER  = SGPIO_SCM_LD_R_<0>
  B33  PETN5  OUT  = GND
  B34  PETP5  OUT  = SGPIO_SCM_DO_R_<1>
  B35  GND_B35  POWER  = SGPIO_SCM_CLK_R_<1>
  B36  PETN6  OUT  = SGPIO_SCM_DI_R_<1>
  B37  PETP6  OUT  = SGPIO_SCM_LD_R_<1>
  B38  GND_B38  POWER  = GND
  B39  PETN7  OUT  = SGPIO_SCM_RESET_R_N
  B40  PETP7  OUT  = SGPIO_SCM_INTR_R1_N
  B41  GND_B41  POWER  = SCM_VDD_RTC
  B42  \prsntb0#\  IN  = FM_AC_PWR_BTN_N
  B43  GND_B43  POWER  = TP_SPI_2_PLD_CLK
  B44  PETN8  OUT  = TP_SPI_2_PLD_CS_N
  B45  PETP8  OUT  = TP_SPI_2_PLD_IO0
  B46  GND_B46  POWER  = TP_SPI_2_PLD_IO1
  B47  PETN9  OUT  = TP_SPI_2_PLD_IO2
  B48  PETP9  OUT  = TP_SPI_2_PLD_IO3
  B49  GND_B49  POWER  = GND
  B50  PETN10  OUT  = USB2_HOST_BMC_B_DP
  B51  PETP10  OUT  = USB2_HOST_BMC_B_DN
  B52  GND_B52  POWER  = GND
  B53  PETN11  OUT  = USB2_CPU0_P1_DP
  B54  PETP11  OUT  = USB2_CPU0_P1_DN
  B55  GND_B55  POWER  = GND
  B56  PETN12  OUT  = USB2_HUB_EXT_DP
  B57  PETP12  OUT  = USB2_HUB_EXT_DN
  B58  GND_B58  POWER  = GND
  B59  PETN13  OUT  = USB3_CPU0_BMC_TX_BUF_C_DP
  B60  PETP13  OUT  = USB3_CPU0_BMC_TX_BUF_C_DN
  B61  GND_B61  POWER  = GND
  B62  PETN14  OUT  = TP_PCIE_TXP<1>
  B63  PETP14  OUT  = TP_PCIE_TXN<1>
  B64  GND_B64  POWER  = GND
  B65  PETN15  OUT  = P2E_MB_BMC_TX_C_DP<0>
  B66  PETP15  OUT  = P2E_MB_BMC_TX_C_DN<0>
  B67  GND_B67  POWER  = GND
  B68  RFU1_NC_B68  TRI  = TP_PCIE_TXP<3>
  B69  RFU1_NC_B69  TRI  = TP_BEEP_LED
  B70  \prsntb3#\  IN  = GND
  G1  G1  POWER  = GND
  G2  G2  POWER  = GND
  G3  G3  POWER  = GND
  G4  G4  POWER  = GND
  G5  G5  POWER  = GND
  OA1  \perst2#\  OUT  = P12V_SCM
  OA2  \perst3#\  OUT  = P12V_SCM
  OA3  \wake#\  IN  = GND
  OA4  RBT_ARB_IN  IN  = GND
  OA5  RBT_ARB_OUT  OUT  = I3C_SCM_0_SCL
  OA6  SLOT_ID1  OUT  = I3C_SCM_0_SDA
  OA7  RBT_TX_EN  OUT  = I3C_SCM_1_SCL
  OA8  RBT_TXD1  OUT  = I3C_SCM_1_SDA
  OA9  RBT_TXD0  OUT  = I3C_SCM_2_SCL
  OA10  GND_OA10  POWER  = I3C_SCM_2_SDA
  OA11  REFCLKN3  OUT  = I3C_SCM_3_SCL
  OA12  REFCLKP3  OUT  = I3C_SCM_3_SDA
  OA13  GND_OA13  POWER  = GND
  OA14  RBT_CLK_IN  OUT  = VIRTUAL_RESEAT
  OB1  NIC_PWR_GOOD  IN  = P12V_SCM
  OB2  MAIN_PWR_EN  OUT  = P12V_SCM
  OB3  \ld#\  OUT  = PRSNT0_N
  OB4  DATA_IN  IN  = GND
  OB5  DATA_OUT  OUT  = UART_BMC_BIC_TX
  OB6  CLK  OUT  = UART_BMC_BIC_BUF_RX
  OB7  SLOT_ID0  OUT  = GND
  OB8  RBT_RXD1  IN  = UART_CPU0_SCM_LVC3_UART1_RX
  OB9  RBT_RXD0  IN  = UART_CPU0_SCM_LVC3_UART1_R1_TX
  OB10  GND_OB10  POWER  = GND
  OB11  REFCLKN2  OUT  = RST_SRST_PLD_BMC_N
  OB12  REFCLKP2  OUT  = SPI_CPU0_LVC3_TPM_CS_N
  OB13  GND_OB13  POWER  = FPGA_IO3V3_RSVD_1
  OB14  RBT_CRS_DV  OUT  = FM_SOL_UART_CH_SEL_R
